(kicad_pcb
	(version 20260206)
	(generator "pcbnew")
	(generator_version "10.0")
	(general
		(thickness 1.6)
		(legacy_teardrops no)
	)
	(paper "A4")
	(title_block
		(title "v1-pdb — T6M_PDB_D_0927_0900.brd")
		(comment 1 "Open CloudServer (Microsoft) / footprints 215-216 of 321")
	)
	(layers
		(0 "F.Cu" signal "TOP")
		(4 "In1.Cu" signal "GND")
		(6 "In2.Cu" signal "IN1")
		(8 "In3.Cu" signal "VCC")
		(10 "In4.Cu" signal "VCC1")
		(12 "In5.Cu" signal "IN2")
		(14 "In6.Cu" signal "GND1")
		(2 "B.Cu" signal "BOTTOM")
		(9 "F.Adhes" user "F.Adhesive")
		(11 "B.Adhes" user "B.Adhesive")
		(13 "F.Paste" user "Package Geometry/Pastemask Top")
		(15 "B.Paste" user "Package Geometry/Pastemask Bottom")
		(5 "F.SilkS" user "Ref Des/Silkscreen Top")
		(7 "B.SilkS" user "Ref Des/Silkscreen Bottom")
		(1 "F.Mask" user "Board Geometry/Soldermask Top")
		(3 "B.Mask" user "Board Geometry/Soldermask Bottom")
		(17 "Dwgs.User" user "User.Drawings")
		(19 "Cmts.User" user "User.Comments")
		(21 "Eco1.User" user "User.Eco1")
		(23 "Eco2.User" user "User.Eco2")
		(25 "Edge.Cuts" user "Board Geometry/Outline")
		(27 "Margin" user)
		(31 "F.CrtYd" user "Package Geometry/Place Bound Top")
		(29 "B.CrtYd" user "Package Geometry/Place Bound Bottom")
		(35 "F.Fab" user "Ref Des/Assembly Top")
		(33 "B.Fab" user "Ref Des/Assembly Bottom")
	)
	(footprint ""
		(layer "F.Cu")
		(at 30.45968 -436.930038)
		(property "Reference" "J5"
			(at -4.20243 -2.774188 0)
			(unlocked yes)
			(layer "F.SilkS")
			(effects
				(font
					(size 0.7874 0.5842)
					(thickness 0.1524)
				)
				(justify left)
			)
		)
		(property "Value" ""
			(at 0 0 0)
			(layer "F.Fab")
			(effects
				(font
					(size 1.27 1.27)
				)
			)
		)
		(duplicate_pad_numbers_are_jumpers no)
		(fp_line
			(start -2.135124 -4.560062)
			(end -2.135124 83.300062)
			(stroke
				(width 0.1524)
				(type default)
			)
			(layer "F.SilkS")
		)
		(fp_line
			(start -2.135124 83.300062)
			(end 7.215124 83.300062)
			(stroke
				(width 0.1524)
				(type default)
			)
			(layer "F.SilkS")
		)
		(fp_line
			(start 7.215124 -4.560062)
			(end -2.135124 -4.560062)
			(stroke
				(width 0.1524)
				(type default)
			)
			(layer "F.SilkS")
		)
		(fp_line
			(start 7.215124 83.300062)
			(end 7.215124 -4.560062)
			(stroke
				(width 0.1524)
				(type default)
			)
			(layer "F.SilkS")
		)
		(fp_poly
			(pts
				(xy -2.74447 -0.00889) (xy -5.44449 -0.708914) (xy -5.44449 0.691134)
			)
			(stroke
				(width 0)
				(type default)
			)
			(fill yes)
			(layer "F.SilkS")
		)
		(fp_poly
			(pts
				(xy -2.28219 -0.127) (xy -4.98221 -0.827024) (xy -4.98221 0.573024)
			)
			(stroke
				(width 0)
				(type default)
			)
			(fill yes)
			(layer "B.SilkS")
		)
		(fp_poly
			(pts
				(xy -0.8636 -0.8636) (xy -0.8636 79.6036) (xy -0.8636 79.629) (xy 5.9436 79.629) (xy 5.9436 79.6036)
				(xy 5.9436 -0.8636) (xy 5.9436 -0.889) (xy -0.8636 -0.889)
			)
			(stroke
				(width 0)
				(type default)
			)
			(fill no)
			(layer "B.CrtYd")
		)
		(fp_rect
			(start -2.135124 -4.560062)
			(end 7.21487 83.300062)
			(stroke
				(width 0)
				(type default)
			)
			(fill no)
			(layer "F.CrtYd")
		)
		(fp_line
			(start -2.135124 -4.560062)
			(end 7.215124 -4.560062)
			(stroke
				(width 0.1)
				(type default)
			)
			(layer "F.Fab")
		)
		(fp_line
			(start -2.135124 83.300062)
			(end -2.135124 -4.560062)
			(stroke
				(width 0.1)
				(type default)
			)
			(layer "F.Fab")
		)
		(fp_line
			(start 7.215124 -4.560062)
			(end 7.215124 83.300062)
			(stroke
				(width 0.1)
				(type default)
			)
			(layer "F.Fab")
		)
		(fp_line
			(start 7.215124 83.300062)
			(end -2.135124 83.300062)
			(stroke
				(width 0.1)
				(type default)
			)
			(layer "F.Fab")
		)
		(fp_text user "32"
			(at -3.655568 78.848458 0)
			(unlocked yes)
			(layer "F.SilkS")
			(effects
				(font
					(size 0.7874 0.5842)
					(thickness 0.1524)
				)
				(justify left)
			)
		)
		(fp_text user "1"
			(at -3.370834 -1.059434 0)
			(unlocked yes)
			(layer "F.SilkS")
			(effects
				(font
					(size 0.7874 0.5842)
					(thickness 0.1524)
				)
				(justify left)
			)
		)
		(fp_text user "33"
			(at 7.649464 81.833466 0)
			(unlocked yes)
			(layer "F.SilkS")
			(effects
				(font
					(size 0.7874 0.5842)
					(thickness 0.1524)
				)
				(justify left)
			)
		)
		(fp_text user "64"
			(at 7.771638 -0.257048 0)
			(unlocked yes)
			(layer "F.SilkS")
			(effects
				(font
					(size 0.7874 0.5842)
					(thickness 0.1524)
				)
				(justify left)
			)
		)
		(fp_text user "32"
			(at -1.12649 78.817216 0)
			(unlocked yes)
			(layer "B.SilkS")
			(effects
				(font
					(size 0.7874 0.5842)
					(thickness 0.1524)
				)
				(justify left mirror)
			)
		)
		(fp_text user "1"
			(at -1.029208 -1.200912 0)
			(unlocked yes)
			(layer "B.SilkS")
			(effects
				(font
					(size 0.7874 0.5842)
					(thickness 0.1524)
				)
				(justify left mirror)
			)
		)
		(fp_text user "33"
			(at 5.666486 81.833466 0)
			(unlocked yes)
			(layer "B.SilkS")
			(effects
				(font
					(size 0.7874 0.5842)
					(thickness 0.1524)
				)
				(justify left mirror)
			)
		)
		(fp_text user "64"
			(at 5.904992 -1.819148 0)
			(unlocked yes)
			(layer "B.SilkS")
			(effects
				(font
					(size 0.7874 0.5842)
					(thickness 0.1524)
				)
				(justify left mirror)
			)
		)
		(pad "1" thru_hole rect
			(at 0 0 270)
			(size 1.6256 1.6256)
			(drill 1.1176)
			(layers "*.Cu" "*.Mask")
			(remove_unused_layers no)
			(net "P12V")
			(clearance 0)
			(padstack
				(mode front_inner_back)
				(layer "Inner"
					(shape circle)
					(size 1.6256 1.6256)
					(clearance 0)
				)
				(layer "B.Cu"
					(shape rect)
					(size 1.6256 1.6256)
					(clearance 0)
				)
			)
		)
		(pad "2" thru_hole circle
			(at 0 2.54 270)
			(size 1.6256 1.6256)
			(drill 1.1176)
			(layers "*.Cu" "*.Mask")
			(remove_unused_layers no)
			(net "P12V")
			(clearance 0)
		)
		(pad "3" thru_hole circle
			(at 0 5.08 270)
			(size 1.6256 1.6256)
			(drill 1.1176)
			(layers "*.Cu" "*.Mask")
			(remove_unused_layers no)
			(net "P12V")
			(clearance 0)
		)
		(pad "4" thru_hole circle
			(at 0 7.62 270)
			(size 1.6256 1.6256)
			(drill 1.1176)
			(layers "*.Cu" "*.Mask")
			(remove_unused_layers no)
			(net "P12V")
			(clearance 0)
		)
		(pad "5" thru_hole circle
			(at 0 10.16 270)
			(size 1.6256 1.6256)
			(drill 1.1176)
			(layers "*.Cu" "*.Mask")
			(remove_unused_layers no)
			(net "P12V")
			(clearance 0)
		)
		(pad "6" thru_hole circle
			(at 0 12.7 270)
			(size 1.6256 1.6256)
			(drill 1.1176)
			(layers "*.Cu" "*.Mask")
			(remove_unused_layers no)
			(net "P12V")
			(clearance 0)
		)
		(pad "7" thru_hole circle
			(at 0 15.24 270)
			(size 1.6256 1.6256)
			(drill 1.1176)
			(layers "*.Cu" "*.Mask")
			(remove_unused_layers no)
			(net "P12V")
			(clearance 0)
		)
		(pad "8" thru_hole circle
			(at 0 17.78 270)
			(size 1.6256 1.6256)
			(drill 1.1176)
			(layers "*.Cu" "*.Mask")
			(remove_unused_layers no)
			(net "P12V")
			(clearance 0)
		)
		(pad "9" thru_hole circle
			(at 0 20.32 270)
			(size 1.6256 1.6256)
			(drill 1.1176)
			(layers "*.Cu" "*.Mask")
			(remove_unused_layers no)
			(net "P12V")
			(clearance 0)
		)
		(pad "10" thru_hole circle
			(at 0 22.86 270)
			(size 1.6256 1.6256)
			(drill 1.1176)
			(layers "*.Cu" "*.Mask")
			(remove_unused_layers no)
			(net "P12V")
			(clearance 0)
		)
		(pad "11" thru_hole circle
			(at 0 25.4 270)
			(size 1.6256 1.6256)
			(drill 1.1176)
			(layers "*.Cu" "*.Mask")
			(remove_unused_layers no)
			(net "P12V")
			(clearance 0)
		)
		(pad "12" thru_hole circle
			(at 0 27.94 270)
			(size 1.6256 1.6256)
			(drill 1.1176)
			(layers "*.Cu" "*.Mask")
			(remove_unused_layers no)
			(net "P12V")
			(clearance 0)
		)
		(pad "13" thru_hole circle
			(at 0 30.48 270)
			(size 1.6256 1.6256)
			(drill 1.1176)
			(layers "*.Cu" "*.Mask")
			(remove_unused_layers no)
			(net "GND")
			(clearance 0)
		)
		(pad "14" thru_hole circle
			(at 0 33.02 270)
			(size 1.6256 1.6256)
			(drill 1.1176)
			(layers "*.Cu" "*.Mask")
			(remove_unused_layers no)
			(net "GND")
			(clearance 0)
		)
		(pad "15" thru_hole circle
			(at 0 35.56 270)
			(size 1.6256 1.6256)
			(drill 1.1176)
			(layers "*.Cu" "*.Mask")
			(remove_unused_layers no)
			(net "GND")
			(clearance 0)
		)
		(pad "16" thru_hole circle
			(at 0 38.1 270)
			(size 1.6256 1.6256)
			(drill 1.1176)
			(layers "*.Cu" "*.Mask")
			(remove_unused_layers no)
			(net "GND")
			(clearance 0)
		)
		(pad "17" thru_hole circle
			(at 0 40.64 270)
			(size 1.6256 1.6256)
			(drill 1.1176)
			(layers "*.Cu" "*.Mask")
			(remove_unused_layers no)
			(net "GND")
			(clearance 0)
		)
		(pad "18" thru_hole circle
			(at 0 43.18 270)
			(size 1.6256 1.6256)
			(drill 1.1176)
			(layers "*.Cu" "*.Mask")
			(remove_unused_layers no)
			(net "GND")
			(clearance 0)
		)
		(pad "19" thru_hole circle
			(at 0 45.72 270)
			(size 1.6256 1.6256)
			(drill 1.1176)
			(layers "*.Cu" "*.Mask")
			(remove_unused_layers no)
			(net "GND")
			(clearance 0)
		)
		(pad "20" thru_hole circle
			(at 0 48.26 270)
			(size 1.6256 1.6256)
			(drill 1.1176)
			(layers "*.Cu" "*.Mask")
			(remove_unused_layers no)
			(net "GND")
			(clearance 0)
		)
		(pad "21" thru_hole circle
			(at 0 50.8 270)
			(size 1.6256 1.6256)
			(drill 1.1176)
			(layers "*.Cu" "*.Mask")
			(remove_unused_layers no)
			(net "GND")
			(clearance 0)
		)
		(pad "22" thru_hole circle
			(at 0 53.34 270)
			(size 1.6256 1.6256)
			(drill 1.1176)
			(layers "*.Cu" "*.Mask")
			(remove_unused_layers no)
			(net "GND")
			(clearance 0)
		)
		(pad "23" thru_hole circle
			(at 0 55.88 270)
			(size 1.6256 1.6256)
			(drill 1.1176)
			(layers "*.Cu" "*.Mask")
			(remove_unused_layers no)
			(net "GND")
			(clearance 0)
		)
		(pad "24" thru_hole circle
			(at 0 58.42 270)
			(size 1.6256 1.6256)
			(drill 1.1176)
			(layers "*.Cu" "*.Mask")
			(remove_unused_layers no)
			(net "GND")
			(clearance 0)
		)
		(pad "25" thru_hole circle
			(at 0 60.96 270)
			(size 1.6256 1.6256)
			(drill 1.1176)
			(layers "*.Cu" "*.Mask")
			(remove_unused_layers no)
			(net "Net_399")
			(clearance 0)
		)
		(pad "26" thru_hole circle
			(at 0 63.5 270)
			(size 1.6256 1.6256)
			(drill 1.1176)
			(layers "*.Cu" "*.Mask")
			(remove_unused_layers no)
			(net "PSU5_REMOTE_N")
			(clearance 0)
		)
		(pad "27" thru_hole circle
			(at 0 66.04 270)
			(size 1.6256 1.6256)
			(drill 1.1176)
			(layers "*.Cu" "*.Mask")
			(remove_unused_layers no)
			(net "PSU5_AC_OK")
			(clearance 0)
		)
		(pad "28" thru_hole circle
			(at 0 68.58 270)
			(size 1.6256 1.6256)
			(drill 1.1176)
			(layers "*.Cu" "*.Mask")
			(remove_unused_layers no)
			(net "PSU5_CSAHRE")
			(clearance 0)
		)
		(pad "29" thru_hole circle
			(at 0 71.12 270)
			(size 1.6256 1.6256)
			(drill 1.1176)
			(layers "*.Cu" "*.Mask")
			(remove_unused_layers no)
			(net "PSU5_PS_ON_N")
			(clearance 0)
		)
		(pad "30" thru_hole circle
			(at 0 73.66 270)
			(size 1.6256 1.6256)
			(drill 1.1176)
			(layers "*.Cu" "*.Mask")
			(remove_unused_layers no)
			(net "PSU5_PS_KILL")
			(clearance 0)
		)
		(pad "31" thru_hole circle
			(at 0 76.2 270)
			(size 1.6256 1.6256)
			(drill 1.1176)
			(layers "*.Cu" "*.Mask")
			(remove_unused_layers no)
			(net "PSU5_RESET")
			(clearance 0)
		)
		(pad "32" thru_hole circle
			(at 0 78.74 270)
			(size 1.6256 1.6256)
			(drill 1.1176)
			(layers "*.Cu" "*.Mask")
			(remove_unused_layers no)
			(net "PSU_ALERT_N")
			(clearance 0)
		)
		(pad "33" thru_hole circle
			(at 5.08 78.74 270)
			(size 1.6256 1.6256)
			(drill 1.1176)
			(layers "*.Cu" "*.Mask")
			(remove_unused_layers no)
			(net "I2C_PSU3_SDA")
			(clearance 0)
		)
		(pad "34" thru_hole circle
			(at 5.08 76.2 270)
			(size 1.6256 1.6256)
			(drill 1.1176)
			(layers "*.Cu" "*.Mask")
			(remove_unused_layers no)
			(net "Net_400")
			(clearance 0)
		)
		(pad "35" thru_hole circle
			(at 5.08 73.66 270)
			(size 1.6256 1.6256)
			(drill 1.1176)
			(layers "*.Cu" "*.Mask")
			(remove_unused_layers no)
			(net "I2C_PSU3_SCL")
			(clearance 0)
		)
		(pad "36" thru_hole circle
			(at 5.08 71.12 270)
			(size 1.6256 1.6256)
			(drill 1.1176)
			(layers "*.Cu" "*.Mask")
			(remove_unused_layers no)
			(net "PSU5_RETURN")
			(clearance 0)
		)
		(pad "37" thru_hole circle
			(at 5.08 68.58 270)
			(size 1.6256 1.6256)
			(drill 1.1176)
			(layers "*.Cu" "*.Mask")
			(remove_unused_layers no)
			(net "PSU5_DC_OK")
			(clearance 0)
		)
		(pad "38" thru_hole circle
			(at 5.08 66.04 270)
			(size 1.6256 1.6256)
			(drill 1.1176)
			(layers "*.Cu" "*.Mask")
			(remove_unused_layers no)
			(net "PSU5_AD0")
			(clearance 0)
		)
		(pad "39" thru_hole circle
			(at 5.08 63.5 270)
			(size 1.6256 1.6256)
			(drill 1.1176)
			(layers "*.Cu" "*.Mask")
			(remove_unused_layers no)
			(net "P12V_STBY")
			(clearance 0)
		)
		(pad "40" thru_hole circle
			(at 5.08 60.96 270)
			(size 1.6256 1.6256)
			(drill 1.1176)
			(layers "*.Cu" "*.Mask")
			(remove_unused_layers no)
			(net "PSU5_REMOTE_P")
			(clearance 0)
		)
		(pad "41" thru_hole circle
			(at 5.08 58.42 270)
			(size 1.6256 1.6256)
			(drill 1.1176)
			(layers "*.Cu" "*.Mask")
			(remove_unused_layers no)
			(net "GND")
			(clearance 0)
		)
		(pad "42" thru_hole circle
			(at 5.08 55.88 270)
			(size 1.6256 1.6256)
			(drill 1.1176)
			(layers "*.Cu" "*.Mask")
			(remove_unused_layers no)
			(net "GND")
			(clearance 0)
		)
		(pad "43" thru_hole circle
			(at 5.08 53.34 270)
			(size 1.6256 1.6256)
			(drill 1.1176)
			(layers "*.Cu" "*.Mask")
			(remove_unused_layers no)
			(net "GND")
			(clearance 0)
		)
		(pad "44" thru_hole circle
			(at 5.08 50.8 270)
			(size 1.6256 1.6256)
			(drill 1.1176)
			(layers "*.Cu" "*.Mask")
			(remove_unused_layers no)
			(net "GND")
			(clearance 0)
		)
		(pad "45" thru_hole circle
			(at 5.08 48.26 270)
			(size 1.6256 1.6256)
			(drill 1.1176)
			(layers "*.Cu" "*.Mask")
			(remove_unused_layers no)
			(net "GND")
			(clearance 0)
		)
		(pad "46" thru_hole circle
			(at 5.08 45.72 270)
			(size 1.6256 1.6256)
			(drill 1.1176)
			(layers "*.Cu" "*.Mask")
			(remove_unused_layers no)
			(net "GND")
			(clearance 0)
		)
		(pad "47" thru_hole circle
			(at 5.08 43.18 270)
			(size 1.6256 1.6256)
			(drill 1.1176)
			(layers "*.Cu" "*.Mask")
			(remove_unused_layers no)
			(net "GND")
			(clearance 0)
		)
		(pad "48" thru_hole circle
			(at 5.08 40.64 270)
			(size 1.6256 1.6256)
			(drill 1.1176)
			(layers "*.Cu" "*.Mask")
			(remove_unused_layers no)
			(net "GND")
			(clearance 0)
		)
		(pad "49" thru_hole circle
			(at 5.08 38.1 270)
			(size 1.6256 1.6256)
			(drill 1.1176)
			(layers "*.Cu" "*.Mask")
			(remove_unused_layers no)
			(net "GND")
			(clearance 0)
		)
		(pad "50" thru_hole circle
			(at 5.08 35.56 270)
			(size 1.6256 1.6256)
			(drill 1.1176)
			(layers "*.Cu" "*.Mask")
			(remove_unused_layers no)
			(net "GND")
			(clearance 0)
		)
		(pad "51" thru_hole circle
			(at 5.08 33.02 270)
			(size 1.6256 1.6256)
			(drill 1.1176)
			(layers "*.Cu" "*.Mask")
			(remove_unused_layers no)
			(net "GND")
			(clearance 0)
		)
		(pad "52" thru_hole circle
			(at 5.08 30.48 270)
			(size 1.6256 1.6256)
			(drill 1.1176)
			(layers "*.Cu" "*.Mask")
			(remove_unused_layers no)
			(net "GND")
			(clearance 0)
		)
		(pad "53" thru_hole circle
			(at 5.08 27.94 270)
			(size 1.6256 1.6256)
			(drill 1.1176)
			(layers "*.Cu" "*.Mask")
			(remove_unused_layers no)
			(net "P12V")
			(clearance 0)
		)
		(pad "54" thru_hole circle
			(at 5.08 25.4 270)
			(size 1.6256 1.6256)
			(drill 1.1176)
			(layers "*.Cu" "*.Mask")
			(remove_unused_layers no)
			(net "P12V")
			(clearance 0)
		)
		(pad "55" thru_hole circle
			(at 5.08 22.86 270)
			(size 1.6256 1.6256)
			(drill 1.1176)
			(layers "*.Cu" "*.Mask")
			(remove_unused_layers no)
			(net "P12V")
			(clearance 0)
		)
		(pad "56" thru_hole circle
			(at 5.08 20.32 270)
			(size 1.6256 1.6256)
			(drill 1.1176)
			(layers "*.Cu" "*.Mask")
			(remove_unused_layers no)
			(net "P12V")
			(clearance 0)
		)
		(pad "57" thru_hole circle
			(at 5.08 17.78 270)
			(size 1.6256 1.6256)
			(drill 1.1176)
			(layers "*.Cu" "*.Mask")
			(remove_unused_layers no)
			(net "P12V")
			(clearance 0)
		)
		(pad "58" thru_hole circle
			(at 5.08 15.24 270)
			(size 1.6256 1.6256)
			(drill 1.1176)
			(layers "*.Cu" "*.Mask")
			(remove_unused_layers no)
			(net "P12V")
			(clearance 0)
		)
		(pad "59" thru_hole circle
			(at 5.08 12.7 270)
			(size 1.6256 1.6256)
			(drill 1.1176)
			(layers "*.Cu" "*.Mask")
			(remove_unused_layers no)
			(net "P12V")
			(clearance 0)
		)
		(pad "60" thru_hole circle
			(at 5.08 10.16 270)
			(size 1.6256 1.6256)
			(drill 1.1176)
			(layers "*.Cu" "*.Mask")
			(remove_unused_layers no)
			(net "P12V")
			(clearance 0)
		)
		(pad "61" thru_hole circle
			(at 5.08 7.62 270)
			(size 1.6256 1.6256)
			(drill 1.1176)
			(layers "*.Cu" "*.Mask")
			(remove_unused_layers no)
			(net "P12V")
			(clearance 0)
		)
		(pad "62" thru_hole circle
			(at 5.08 5.08 270)
			(size 1.6256 1.6256)
			(drill 1.1176)
			(layers "*.Cu" "*.Mask")
			(remove_unused_layers no)
			(net "P12V")
			(clearance 0)
		)
		(pad "63" thru_hole circle
			(at 5.08 2.54 270)
			(size 1.6256 1.6256)
			(drill 1.1176)
			(layers "*.Cu" "*.Mask")
			(remove_unused_layers no)
			(net "P12V")
			(clearance 0)
		)
		(pad "64" thru_hole circle
			(at 5.08 0 270)
			(size 1.6256 1.6256)
			(drill 1.1176)
			(layers "*.Cu" "*.Mask")
			(remove_unused_layers no)
			(net "P12V")
			(clearance 0)
		)
	)
	(footprint ""
		(layer "F.Cu")
		(at 14.923008 -330.497434 -90)
		(property "Reference" "R35"
			(at 3.685032 -0.234188 90)
			(unlocked yes)
			(layer "F.SilkS")
			(effects
				(font
					(size 0.7874 0.5842)
					(thickness 0.1524)
				)
				(justify left)
			)
		)
		(property "Value" ""
			(at 0 0 270)
			(layer "F.Fab")
			(effects
				(font
					(size 1.27 1.27)
				)
			)
		)
		(duplicate_pad_numbers_are_jumpers no)
		(fp_line
			(start -0.7874 0.4064)
			(end -0.7874 -0.4064)
			(stroke
				(width 0.1524)
				(type default)
			)
			(layer "F.SilkS")
		)
		(fp_line
			(start 0.7874 0.4064)
			(end -0.7874 0.4064)
			(stroke
				(width 0.1524)
				(type default)
			)
			(layer "F.SilkS")
		)
		(fp_line
			(start -0.7874 -0.4064)
			(end 0.7874 -0.4064)
			(stroke
				(width 0.1524)
				(type default)
			)
			(layer "F.SilkS")
		)
		(fp_line
			(start 0.7874 -0.4064)
			(end 0.7874 0.4064)
			(stroke
				(width 0.1524)
				(type default)
			)
			(layer "F.SilkS")
		)
		(fp_poly
			(pts
				(xy -0.508 0.2794) (xy -0.508 0.2286) (xy -0.635 0.2286) (xy -0.635 -0.254) (xy -0.5334 -0.254)
				(xy -0.5334 -0.2794) (xy 0.5334 -0.2794) (xy 0.5334 -0.254) (xy 0.635 -0.254) (xy 0.635 0.254) (xy 0.5334 0.254)
				(xy 0.5334 0.2794)
			)
			(stroke
				(width 0)
				(type default)
			)
			(fill no)
			(layer "F.CrtYd")
		)
		(pad "1" smd rect
			(at 0.40005 0 270)
			(size 0.4572 0.508)
			(layers "F.Cu" "F.Mask" "F.Paste")
			(net "P3V3")
		)
		(pad "2" smd rect
			(at -0.40005 0 270)
			(size 0.4572 0.508)
			(layers "F.Cu" "F.Mask" "F.Paste")
			(net "FRU_A1")
		)
	)
)
